(kicad_pcb
	(version 20260206)
	(generator "pcbnew")
	(generator_version "10.0")
	(general
		(thickness 1.6)
		(legacy_teardrops no)
	)
	(paper "A4")
	(title_block
		(title "01162023_DA0F0TEBIF0_F0T_Expander_BD_F_brd_V02_OCP.brd")
		(comment 1 "Grand Teton / footprints 7268-7275 of 9728")
	)
	(layers
		(0 "F.Cu" signal "TOP")
		(4 "In1.Cu" signal "GND")
		(6 "In2.Cu" signal "VCC")
		(8 "In3.Cu" signal "VCC1")
		(10 "In4.Cu" signal "GND1")
		(12 "In5.Cu" signal "IN1")
		(14 "In6.Cu" signal "GND2")
		(16 "In7.Cu" signal "IN2")
		(18 "In8.Cu" signal "GND3")
		(20 "In9.Cu" signal "IN3")
		(22 "In10.Cu" signal "GND4")
		(24 "In11.Cu" signal "IN4")
		(26 "In12.Cu" signal "GND5")
		(28 "In13.Cu" signal "IN5")
		(30 "In14.Cu" signal "GND6")
		(32 "In15.Cu" signal "IN6")
		(34 "In16.Cu" signal "GND7")
		(2 "B.Cu" signal "BOTTOM")
		(9 "F.Adhes" user "F.Adhesive")
		(11 "B.Adhes" user "B.Adhesive")
		(13 "F.Paste" user "Package Geometry/Pastemask Top")
		(15 "B.Paste" user "Package Geometry/Pastemask Bottom")
		(5 "F.SilkS" user "Ref Des/Silkscreen Top")
		(7 "B.SilkS" user "Ref Des/Silkscreen Bottom")
		(1 "F.Mask" user "Board Geometry/Soldermask Top")
		(3 "B.Mask" user "Board Geometry/Soldermask Bottom")
		(17 "Dwgs.User" user "User.Drawings")
		(19 "Cmts.User" user "User.Comments")
		(21 "Eco1.User" user "User.Eco1")
		(23 "Eco2.User" user "User.Eco2")
		(25 "Edge.Cuts" user "Board Geometry/Outline")
		(27 "Margin" user)
		(31 "F.CrtYd" user "Package Geometry/Place Bound Top")
		(29 "B.CrtYd" user "Package Geometry/Place Bound Bottom")
		(35 "F.Fab" user "Ref Des/Assembly Top")
		(33 "B.Fab" user "Ref Des/Assembly Bottom")
	)
	(footprint ""
		(layer "B.Cu")
		(at 206.389986 -251.73051 90)
		(property "Reference" "U423"
			(at -1.153414 7.503668 0)
			(unlocked yes)
			(layer "B.SilkS")
			(effects
				(font
					(size 0.7874 0.5842)
					(thickness 0.1524)
				)
				(justify left mirror)
			)
		)
		(property "Value" ""
			(at 0 0 90)
			(layer "B.Fab")
			(effects
				(font
					(size 1.27 1.27)
				)
				(justify mirror)
			)
		)
		(duplicate_pad_numbers_are_jumpers no)
		(fp_line
			(start 1.8542 -3.949954)
			(end 1.8542 3.949954)
			(stroke
				(width 0.1524)
				(type default)
			)
			(layer "B.SilkS")
		)
		(fp_line
			(start 1.282954 -3.949954)
			(end 1.8542 -3.949954)
			(stroke
				(width 0.1524)
				(type default)
			)
			(layer "B.SilkS")
		)
		(fp_line
			(start -1.282954 -3.949954)
			(end 0 -2.667)
			(stroke
				(width 0.1524)
				(type default)
			)
			(layer "B.SilkS")
		)
		(fp_line
			(start -1.8542 -3.949954)
			(end -1.282954 -3.949954)
			(stroke
				(width 0.1524)
				(type default)
			)
			(layer "B.SilkS")
		)
		(fp_line
			(start 0 -2.667)
			(end 1.282954 -3.949954)
			(stroke
				(width 0.1524)
				(type default)
			)
			(layer "B.SilkS")
		)
		(fp_line
			(start 1.8542 3.949954)
			(end -1.8542 3.949954)
			(stroke
				(width 0.1524)
				(type default)
			)
			(layer "B.SilkS")
		)
		(fp_line
			(start -1.8542 3.949954)
			(end -1.8542 -3.949954)
			(stroke
				(width 0.1524)
				(type default)
			)
			(layer "B.SilkS")
		)
		(fp_poly
			(pts
				(xy 4.8006 -4.08305) (xy 4.8006 -3.06705) (xy 3.7846 -3.57505)
			)
			(stroke
				(width 0)
				(type default)
			)
			(fill yes)
			(layer "B.SilkS")
		)
		(fp_line
			(start 2.249932 -3.949954)
			(end 2.249932 3.949954)
			(stroke
				(width 0.1)
				(type default)
			)
			(layer "B.Fab")
		)
		(fp_line
			(start -2.249932 -3.949954)
			(end 2.249932 -3.949954)
			(stroke
				(width 0.1)
				(type default)
			)
			(layer "B.Fab")
		)
		(fp_line
			(start 2.249932 3.949954)
			(end -2.249932 3.949954)
			(stroke
				(width 0.1)
				(type default)
			)
			(layer "B.Fab")
		)
		(fp_line
			(start -2.249932 3.949954)
			(end -2.249932 -3.949954)
			(stroke
				(width 0.1)
				(type default)
			)
			(layer "B.Fab")
		)
		(fp_poly
			(pts
				(xy 4.8006 -4.08305) (xy 4.8006 -3.06705) (xy 3.7846 -3.57505)
			)
			(stroke
				(width 0)
				(type default)
			)
			(fill yes)
			(layer "B.Fab")
		)
		(pad "1" smd rect
			(at 2.800096 -3.57505)
			(size 0.3048 1.6002)
			(layers "B.Cu" "B.Mask" "B.Paste")
			(net "PEX_MUX_A0")
		)
		(pad "2" smd rect
			(at 2.800096 -2.925064)
			(size 0.3048 1.6002)
			(layers "B.Cu" "B.Mask" "B.Paste")
			(net "PEX_MUX_A1")
		)
		(pad "3" smd rect
			(at 2.800096 -2.275078)
			(size 0.3048 1.6002)
			(layers "B.Cu" "B.Mask" "B.Paste")
			(net "RST_PEX_MUX_R_N")
		)
		(pad "4" smd rect
			(at 2.800096 -1.625092)
			(size 0.3048 1.6002)
			(layers "B.Cu" "B.Mask" "B.Paste")
			(net "SMB_PEX0_MUX_SDA")
		)
		(pad "5" smd rect
			(at 2.800096 -0.975106)
			(size 0.3048 1.6002)
			(layers "B.Cu" "B.Mask" "B.Paste")
			(net "SMB_PEX0_MUX_SCL")
		)
		(pad "6" smd rect
			(at 2.800096 -0.32512)
			(size 0.3048 1.6002)
			(layers "B.Cu" "B.Mask" "B.Paste")
			(net "SMB_PEX1_MUX_SDA")
		)
		(pad "7" smd rect
			(at 2.800096 0.32512)
			(size 0.3048 1.6002)
			(layers "B.Cu" "B.Mask" "B.Paste")
			(net "SMB_PEX1_MUX_SCL")
		)
		(pad "8" smd rect
			(at 2.800096 0.975106)
			(size 0.3048 1.6002)
			(layers "B.Cu" "B.Mask" "B.Paste")
			(net "SMB_PEX2_MUX_SDA")
		)
		(pad "9" smd rect
			(at 2.800096 1.625092)
			(size 0.3048 1.6002)
			(layers "B.Cu" "B.Mask" "B.Paste")
			(net "SMB_PEX2_MUX_SCL")
		)
		(pad "10" smd rect
			(at 2.800096 2.275078)
			(size 0.3048 1.6002)
			(layers "B.Cu" "B.Mask" "B.Paste")
			(net "SMB_PEX3_MUX_SDA")
		)
		(pad "11" smd rect
			(at 2.800096 2.925064)
			(size 0.3048 1.6002)
			(layers "B.Cu" "B.Mask" "B.Paste")
			(net "SMB_PEX3_MUX_SCL")
		)
		(pad "12" smd rect
			(at 2.800096 3.57505)
			(size 0.3048 1.6002)
			(layers "B.Cu" "B.Mask" "B.Paste")
			(net "GND")
		)
		(pad "13" smd rect
			(at -2.800096 3.57505)
			(size 0.3048 1.6002)
			(layers "B.Cu" "B.Mask" "B.Paste")
			(net "Net_9184")
		)
		(pad "14" smd rect
			(at -2.800096 2.925064)
			(size 0.3048 1.6002)
			(layers "B.Cu" "B.Mask" "B.Paste")
			(net "Net_9188")
		)
		(pad "15" smd rect
			(at -2.800096 2.275078)
			(size 0.3048 1.6002)
			(layers "B.Cu" "B.Mask" "B.Paste")
			(net "Net_9183")
		)
		(pad "16" smd rect
			(at -2.800096 1.625092)
			(size 0.3048 1.6002)
			(layers "B.Cu" "B.Mask" "B.Paste")
			(net "Net_9187")
		)
		(pad "17" smd rect
			(at -2.800096 0.975106)
			(size 0.3048 1.6002)
			(layers "B.Cu" "B.Mask" "B.Paste")
			(net "Net_9182")
		)
		(pad "18" smd rect
			(at -2.800096 0.32512)
			(size 0.3048 1.6002)
			(layers "B.Cu" "B.Mask" "B.Paste")
			(net "Net_9186")
		)
		(pad "19" smd rect
			(at -2.800096 -0.32512)
			(size 0.3048 1.6002)
			(layers "B.Cu" "B.Mask" "B.Paste")
			(net "Net_9181")
		)
		(pad "20" smd rect
			(at -2.800096 -0.975106)
			(size 0.3048 1.6002)
			(layers "B.Cu" "B.Mask" "B.Paste")
			(net "Net_9185")
		)
		(pad "21" smd rect
			(at -2.800096 -1.625092)
			(size 0.3048 1.6002)
			(layers "B.Cu" "B.Mask" "B.Paste")
			(net "PEX_MUX_A2")
		)
		(pad "22" smd rect
			(at -2.800096 -2.275078)
			(size 0.3048 1.6002)
			(layers "B.Cu" "B.Mask" "B.Paste")
			(net "SMB_PEX_MUX_SCL")
		)
		(pad "23" smd rect
			(at -2.800096 -2.925064)
			(size 0.3048 1.6002)
			(layers "B.Cu" "B.Mask" "B.Paste")
			(net "SMB_PEX_MUX_SDA")
		)
		(pad "24" smd rect
			(at -2.800096 -3.57505)
			(size 0.3048 1.6002)
			(layers "B.Cu" "B.Mask" "B.Paste")
			(net "P1V8_PEX")
		)
	)
	(footprint ""
		(layer "B.Cu")
		(at 61.549788 -299.699934 -90)
		(property "Reference" "C1239"
			(at 0 0 90)
			(layer "B.SilkS")
			(hide yes)
			(effects
				(font
					(size 1.27 1.27)
				)
				(justify mirror)
			)
		)
		(property "Value" ""
			(at 0 0 90)
			(layer "B.Fab")
			(effects
				(font
					(size 1.27 1.27)
				)
				(justify mirror)
			)
		)
		(duplicate_pad_numbers_are_jumpers no)
		(fp_line
			(start -0.299974 0.150114)
			(end 0.299974 0.150114)
			(stroke
				(width 0.1)
				(type default)
			)
			(layer "B.Fab")
		)
		(fp_line
			(start 0.299974 0.150114)
			(end 0.299974 -0.150114)
			(stroke
				(width 0.1)
				(type default)
			)
			(layer "B.Fab")
		)
		(fp_line
			(start -0.299974 -0.150114)
			(end -0.299974 0.150114)
			(stroke
				(width 0.1)
				(type default)
			)
			(layer "B.Fab")
		)
		(fp_line
			(start 0.299974 -0.150114)
			(end -0.299974 -0.150114)
			(stroke
				(width 0.1)
				(type default)
			)
			(layer "B.Fab")
		)
		(pad "1" smd rect
			(at 0.2667 0 90)
			(size 0.3048 0.381)
			(layers "B.Cu" "B.Mask" "B.Paste")
			(net "P0V8_SERDES_VDDA_PEX0")
		)
		(pad "2" smd rect
			(at -0.2667 0 90)
			(size 0.3048 0.381)
			(layers "B.Cu" "B.Mask" "B.Paste")
			(net "GND")
		)
	)
	(footprint ""
		(layer "B.Cu")
		(at 294.69969 -292.099746 90)
		(property "Reference" "C1727"
			(at 0 0 90)
			(layer "B.SilkS")
			(hide yes)
			(effects
				(font
					(size 1.27 1.27)
				)
				(justify mirror)
			)
		)
		(property "Value" ""
			(at 0 0 90)
			(layer "B.Fab")
			(effects
				(font
					(size 1.27 1.27)
				)
				(justify mirror)
			)
		)
		(duplicate_pad_numbers_are_jumpers no)
		(fp_line
			(start 0.299974 -0.150114)
			(end -0.299974 -0.150114)
			(stroke
				(width 0.1)
				(type default)
			)
			(layer "B.Fab")
		)
		(fp_line
			(start -0.299974 -0.150114)
			(end -0.299974 0.150114)
			(stroke
				(width 0.1)
				(type default)
			)
			(layer "B.Fab")
		)
		(fp_line
			(start 0.299974 0.150114)
			(end 0.299974 -0.150114)
			(stroke
				(width 0.1)
				(type default)
			)
			(layer "B.Fab")
		)
		(fp_line
			(start -0.299974 0.150114)
			(end 0.299974 0.150114)
			(stroke
				(width 0.1)
				(type default)
			)
			(layer "B.Fab")
		)
		(pad "1" smd rect
			(at 0.2667 0 270)
			(size 0.3048 0.381)
			(layers "B.Cu" "B.Mask" "B.Paste")
			(net "P0V8_SERDES_VDDA_PEX2")
		)
		(pad "2" smd rect
			(at -0.2667 0 270)
			(size 0.3048 0.381)
			(layers "B.Cu" "B.Mask" "B.Paste")
			(net "GND")
		)
	)
	(footprint ""
		(layer "B.Cu")
		(at 58.699908 -290.199826 90)
		(property "Reference" "C1183"
			(at 0 0 90)
			(layer "B.SilkS")
			(hide yes)
			(effects
				(font
					(size 1.27 1.27)
				)
				(justify mirror)
			)
		)
		(property "Value" ""
			(at 0 0 90)
			(layer "B.Fab")
			(effects
				(font
					(size 1.27 1.27)
				)
				(justify mirror)
			)
		)
		(duplicate_pad_numbers_are_jumpers no)
		(fp_line
			(start 0.299974 -0.150114)
			(end -0.299974 -0.150114)
			(stroke
				(width 0.1)
				(type default)
			)
			(layer "B.Fab")
		)
		(fp_line
			(start -0.299974 -0.150114)
			(end -0.299974 0.150114)
			(stroke
				(width 0.1)
				(type default)
			)
			(layer "B.Fab")
		)
		(fp_line
			(start 0.299974 0.150114)
			(end 0.299974 -0.150114)
			(stroke
				(width 0.1)
				(type default)
			)
			(layer "B.Fab")
		)
		(fp_line
			(start -0.299974 0.150114)
			(end 0.299974 0.150114)
			(stroke
				(width 0.1)
				(type default)
			)
			(layer "B.Fab")
		)
		(pad "1" smd rect
			(at 0.2667 0 270)
			(size 0.3048 0.381)
			(layers "B.Cu" "B.Mask" "B.Paste")
			(net "P0V8_SERDES_VDDA_PEX0")
		)
		(pad "2" smd rect
			(at -0.2667 0 270)
			(size 0.3048 0.381)
			(layers "B.Cu" "B.Mask" "B.Paste")
			(net "GND")
		)
	)
	(footprint ""
		(layer "B.Cu")
		(at 107.697778 -327.366122 180)
		(property "Reference" "C2698"
			(at 0 0 0)
			(layer "B.SilkS")
			(hide yes)
			(effects
				(font
					(size 1.27 1.27)
				)
				(justify mirror)
			)
		)
		(property "Value" ""
			(at 0 0 0)
			(layer "B.Fab")
			(effects
				(font
					(size 1.27 1.27)
				)
				(justify mirror)
			)
		)
		(duplicate_pad_numbers_are_jumpers no)
		(fp_line
			(start 0.7874 0.4064)
			(end 0.7874 -0.4064)
			(stroke
				(width 0.1524)
				(type default)
			)
			(layer "B.SilkS")
		)
		(fp_line
			(start 0.7874 -0.4064)
			(end -0.7874 -0.4064)
			(stroke
				(width 0.1524)
				(type default)
			)
			(layer "B.SilkS")
		)
		(fp_line
			(start -0.7874 0.4064)
			(end 0.7874 0.4064)
			(stroke
				(width 0.1524)
				(type default)
			)
			(layer "B.SilkS")
		)
		(fp_line
			(start -0.7874 -0.4064)
			(end -0.7874 0.4064)
			(stroke
				(width 0.1524)
				(type default)
			)
			(layer "B.SilkS")
		)
		(fp_line
			(start 0.67945 0.3048)
			(end 0.67945 -0.305054)
			(stroke
				(width 0.1)
				(type default)
			)
			(layer "B.Fab")
		)
		(fp_line
			(start 0.67945 -0.305054)
			(end 0.12065 -0.305054)
			(stroke
				(width 0.1)
				(type default)
			)
			(layer "B.Fab")
		)
		(fp_line
			(start 0.12065 0.3048)
			(end 0.67945 0.3048)
			(stroke
				(width 0.1)
				(type default)
			)
			(layer "B.Fab")
		)
		(fp_line
			(start 0.12065 0.2794)
			(end 0.12065 0.3048)
			(stroke
				(width 0.1)
				(type default)
			)
			(layer "B.Fab")
		)
		(fp_line
			(start 0.12065 -0.2794)
			(end -0.12065 -0.2794)
			(stroke
				(width 0.1)
				(type default)
			)
			(layer "B.Fab")
		)
		(fp_line
			(start 0.12065 -0.305054)
			(end 0.12065 -0.2794)
			(stroke
				(width 0.1)
				(type default)
			)
			(layer "B.Fab")
		)
		(fp_line
			(start -0.120396 0.3048)
			(end -0.120396 0.2794)
			(stroke
				(width 0.1)
				(type default)
			)
			(layer "B.Fab")
		)
		(fp_line
			(start -0.120396 0.2794)
			(end 0.12065 0.2794)
			(stroke
				(width 0.1)
				(type default)
			)
			(layer "B.Fab")
		)
		(fp_line
			(start -0.12065 -0.2794)
			(end -0.12065 -0.3048)
			(stroke
				(width 0.1)
				(type default)
			)
			(layer "B.Fab")
		)
		(fp_line
			(start -0.12065 -0.3048)
			(end -0.67945 -0.3048)
			(stroke
				(width 0.1)
				(type default)
			)
			(layer "B.Fab")
		)
		(fp_line
			(start -0.67945 0.3048)
			(end -0.120396 0.3048)
			(stroke
				(width 0.1)
				(type default)
			)
			(layer "B.Fab")
		)
		(fp_line
			(start -0.67945 -0.3048)
			(end -0.67945 0.3048)
			(stroke
				(width 0.1)
				(type default)
			)
			(layer "B.Fab")
		)
		(pad "1" smd circle
			(at 0.40005 0)
			(size 0 0)
			(layers "B.Cu" "B.Mask" "B.Paste")
			(net "P3V3_CLK_BUFFER_9ZXL0451E_VZX3P3")
		)
		(pad "2" smd circle
			(at -0.40005 0)
			(size 0 0)
			(layers "B.Cu" "B.Mask" "B.Paste")
			(net "GND")
		)
	)
	(footprint ""
		(layer "B.Cu")
		(at 3.092704 -273.296888)
		(property "Reference" "C4232"
			(at 0 0 0)
			(layer "B.SilkS")
			(hide yes)
			(effects
				(font
					(size 1.27 1.27)
				)
				(justify mirror)
			)
		)
		(property "Value" ""
			(at 0 0 0)
			(layer "B.Fab")
			(effects
				(font
					(size 1.27 1.27)
				)
				(justify mirror)
			)
		)
		(duplicate_pad_numbers_are_jumpers no)
		(fp_line
			(start -1.2954 -0.5842)
			(end -1.2954 0.5842)
			(stroke
				(width 0.1524)
				(type default)
			)
			(layer "B.SilkS")
		)
		(fp_line
			(start -1.2954 0.5842)
			(end 1.2954 0.5842)
			(stroke
				(width 0.1524)
				(type default)
			)
			(layer "B.SilkS")
		)
		(fp_line
			(start 1.2954 -0.5842)
			(end -1.2954 -0.5842)
			(stroke
				(width 0.1524)
				(type default)
			)
			(layer "B.SilkS")
		)
		(fp_line
			(start 1.2954 0.5842)
			(end 1.2954 -0.5842)
			(stroke
				(width 0.1524)
				(type default)
			)
			(layer "B.SilkS")
		)
		(fp_line
			(start -1.1938 -0.4064)
			(end -1.1938 0.4064)
			(stroke
				(width 0.1)
				(type default)
			)
			(layer "B.Fab")
		)
		(fp_line
			(start -1.1938 0.4064)
			(end -0.8636 0.4064)
			(stroke
				(width 0.1)
				(type default)
			)
			(layer "B.Fab")
		)
		(fp_line
			(start -0.8636 -0.4572)
			(end -0.8636 -0.4064)
			(stroke
				(width 0.1)
				(type default)
			)
			(layer "B.Fab")
		)
		(fp_line
			(start -0.8636 -0.4064)
			(end -1.1938 -0.4064)
			(stroke
				(width 0.1)
				(type default)
			)
			(layer "B.Fab")
		)
		(fp_line
			(start -0.8636 0.4064)
			(end -0.8636 0.4572)
			(stroke
				(width 0.1)
				(type default)
			)
			(layer "B.Fab")
		)
		(fp_line
			(start -0.8636 0.4572)
			(end 0.8636 0.4572)
			(stroke
				(width 0.1)
				(type default)
			)
			(layer "B.Fab")
		)
		(fp_line
			(start 0.8636 -0.4572)
			(end -0.8636 -0.4572)
			(stroke
				(width 0.1)
				(type default)
			)
			(layer "B.Fab")
		)
		(fp_line
			(start 0.8636 -0.4064)
			(end 0.8636 -0.4572)
			(stroke
				(width 0.1)
				(type default)
			)
			(layer "B.Fab")
		)
		(fp_line
			(start 0.8636 0.4064)
			(end 1.1938 0.4064)
			(stroke
				(width 0.1)
				(type default)
			)
			(layer "B.Fab")
		)
		(fp_line
			(start 0.8636 0.4572)
			(end 0.8636 0.4064)
			(stroke
				(width 0.1)
				(type default)
			)
			(layer "B.Fab")
		)
		(fp_line
			(start 1.1938 -0.4064)
			(end 0.8636 -0.4064)
			(stroke
				(width 0.1)
				(type default)
			)
			(layer "B.Fab")
		)
		(fp_line
			(start 1.1938 0.4064)
			(end 1.1938 -0.4064)
			(stroke
				(width 0.1)
				(type default)
			)
			(layer "B.Fab")
		)
		(pad "1" smd rect
			(at 0.7366 0 270)
			(size 0.7112 0.8128)
			(layers "B.Cu" "B.Mask" "B.Paste")
			(net "P1V25_PEX0")
		)
		(pad "2" smd rect
			(at -0.7366 0 270)
			(size 0.7112 0.8128)
			(layers "B.Cu" "B.Mask" "B.Paste")
			(net "GND")
		)
	)
	(footprint ""
		(layer "B.Cu")
		(at 68.199762 -293.52494 180)
		(property "Reference" "C1105"
			(at 0 0 0)
			(layer "B.SilkS")
			(hide yes)
			(effects
				(font
					(size 1.27 1.27)
				)
				(justify mirror)
			)
		)
		(property "Value" ""
			(at 0 0 0)
			(layer "B.Fab")
			(effects
				(font
					(size 1.27 1.27)
				)
				(justify mirror)
			)
		)
		(duplicate_pad_numbers_are_jumpers no)
		(fp_line
			(start 0.299974 0.150114)
			(end 0.299974 -0.150114)
			(stroke
				(width 0.1)
				(type default)
			)
			(layer "B.Fab")
		)
		(fp_line
			(start 0.299974 -0.150114)
			(end -0.299974 -0.150114)
			(stroke
				(width 0.1)
				(type default)
			)
			(layer "B.Fab")
		)
		(fp_line
			(start -0.299974 0.150114)
			(end 0.299974 0.150114)
			(stroke
				(width 0.1)
				(type default)
			)
			(layer "B.Fab")
		)
		(fp_line
			(start -0.299974 -0.150114)
			(end -0.299974 0.150114)
			(stroke
				(width 0.1)
				(type default)
			)
			(layer "B.Fab")
		)
		(pad "1" smd rect
			(at 0.2667 0)
			(size 0.3048 0.381)
			(layers "B.Cu" "B.Mask" "B.Paste")
			(net "P0V8_PEX0")
		)
		(pad "2" smd rect
			(at -0.2667 0)
			(size 0.3048 0.381)
			(layers "B.Cu" "B.Mask" "B.Paste")
			(net "GND")
		)
	)
	(footprint ""
		(layer "B.Cu")
		(at 168.625012 -297.79976 -90)
		(property "Reference" "C1395"
			(at 0 0 90)
			(layer "B.SilkS")
			(hide yes)
			(effects
				(font
					(size 1.27 1.27)
				)
				(justify mirror)
			)
		)
		(property "Value" ""
			(at 0 0 90)
			(layer "B.Fab")
			(effects
				(font
					(size 1.27 1.27)
				)
				(justify mirror)
			)
		)
		(duplicate_pad_numbers_are_jumpers no)
		(fp_line
			(start -0.299974 0.150114)
			(end 0.299974 0.150114)
			(stroke
				(width 0.1)
				(type default)
			)
			(layer "B.Fab")
		)
		(fp_line
			(start 0.299974 0.150114)
			(end 0.299974 -0.150114)
			(stroke
				(width 0.1)
				(type default)
			)
			(layer "B.Fab")
		)
		(fp_line
			(start -0.299974 -0.150114)
			(end -0.299974 0.150114)
			(stroke
				(width 0.1)
				(type default)
			)
			(layer "B.Fab")
		)
		(fp_line
			(start 0.299974 -0.150114)
			(end -0.299974 -0.150114)
			(stroke
				(width 0.1)
				(type default)
			)
			(layer "B.Fab")
		)
		(pad "1" smd rect
			(at 0.2667 0 90)
			(size 0.3048 0.381)
			(layers "B.Cu" "B.Mask" "B.Paste")
			(net "P0V8_PEX1")
		)
		(pad "2" smd rect
			(at -0.2667 0 90)
			(size 0.3048 0.381)
			(layers "B.Cu" "B.Mask" "B.Paste")
			(net "GND")
		)
	)
)
